(kicad_pcb
	(version 20260206)
	(generator "pcbnew")
	(generator_version "10.0")
	(general
		(thickness 1.6)
		(legacy_teardrops no)
	)
	(paper "A4")
	(title_block
		(title "04192023_DAF0TMB3IC0_F0TG_MB_C_brd_V02_OCP.brd")
		(comment 1 "Grand Teton / footprints 5362-5368 of 8354")
	)
	(layers
		(0 "F.Cu" signal "TOP")
		(4 "In1.Cu" signal "GND")
		(6 "In2.Cu" signal "IN1")
		(8 "In3.Cu" signal "GND1")
		(10 "In4.Cu" signal "IN2")
		(12 "In5.Cu" signal "GND2")
		(14 "In6.Cu" signal "IN3")
		(16 "In7.Cu" signal "GND3")
		(18 "In8.Cu" signal "VCC")
		(20 "In9.Cu" signal "VCC1")
		(22 "In10.Cu" signal "GND4")
		(24 "In11.Cu" signal "IN4")
		(26 "In12.Cu" signal "GND5")
		(28 "In13.Cu" signal "IN5")
		(30 "In14.Cu" signal "GND6")
		(32 "In15.Cu" signal "IN6")
		(34 "In16.Cu" signal "GND7")
		(2 "B.Cu" signal "BOTTOM")
		(9 "F.Adhes" user "F.Adhesive")
		(11 "B.Adhes" user "B.Adhesive")
		(13 "F.Paste" user "Package Geometry/Pastemask Top")
		(15 "B.Paste" user "Package Geometry/Pastemask Bottom")
		(5 "F.SilkS" user "Ref Des/Silkscreen Top")
		(7 "B.SilkS" user "Ref Des/Silkscreen Bottom")
		(1 "F.Mask" user "Board Geometry/Soldermask Top")
		(3 "B.Mask" user "Board Geometry/Soldermask Bottom")
		(17 "Dwgs.User" user "User.Drawings")
		(19 "Cmts.User" user "User.Comments")
		(21 "Eco1.User" user "User.Eco1")
		(23 "Eco2.User" user "User.Eco2")
		(25 "Edge.Cuts" user "Board Geometry/Outline")
		(27 "Margin" user)
		(31 "F.CrtYd" user "Package Geometry/Place Bound Top")
		(29 "B.CrtYd" user "Package Geometry/Place Bound Bottom")
		(35 "F.Fab" user "Ref Des/Assembly Top")
		(33 "B.Fab" user "Ref Des/Assembly Bottom")
	)
	(footprint ""
		(layer "B.Cu")
		(at 66.583814 -386.766562 90)
		(property "Reference" "C280"
			(at 0 0 90)
			(layer "B.SilkS")
			(hide yes)
			(effects
				(font
					(size 1.27 1.27)
				)
				(justify mirror)
			)
		)
		(property "Value" ""
			(at 0 0 90)
			(layer "B.Fab")
			(effects
				(font
					(size 1.27 1.27)
				)
				(justify mirror)
			)
		)
		(duplicate_pad_numbers_are_jumpers no)
		(fp_line
			(start 0.299974 -0.150114)
			(end -0.299974 -0.150114)
			(stroke
				(width 0.1)
				(type default)
			)
			(layer "B.Fab")
		)
		(fp_line
			(start -0.299974 -0.150114)
			(end -0.299974 0.150114)
			(stroke
				(width 0.1)
				(type default)
			)
			(layer "B.Fab")
		)
		(fp_line
			(start 0.299974 0.150114)
			(end 0.299974 -0.150114)
			(stroke
				(width 0.1)
				(type default)
			)
			(layer "B.Fab")
		)
		(fp_line
			(start -0.299974 0.150114)
			(end 0.299974 0.150114)
			(stroke
				(width 0.1)
				(type default)
			)
			(layer "B.Fab")
		)
		(pad "1" smd rect
			(at 0.2667 0 270)
			(size 0.3048 0.381)
			(layers "B.Cu" "B.Mask" "B.Paste")
			(net "P0V9_CPU1_RT0_2A")
		)
		(pad "2" smd rect
			(at -0.2667 0 270)
			(size 0.3048 0.381)
			(layers "B.Cu" "B.Mask" "B.Paste")
			(net "GND")
		)
	)
	(footprint ""
		(layer "B.Cu")
		(at 131.849114 -33.199578 -90)
		(property "Reference" "C6050"
			(at 0 0 90)
			(layer "B.SilkS")
			(hide yes)
			(effects
				(font
					(size 1.27 1.27)
				)
				(justify mirror)
			)
		)
		(property "Value" ""
			(at 0 0 90)
			(layer "B.Fab")
			(effects
				(font
					(size 1.27 1.27)
				)
				(justify mirror)
			)
		)
		(duplicate_pad_numbers_are_jumpers no)
		(fp_line
			(start -0.7874 0.4064)
			(end 0.7874 0.4064)
			(stroke
				(width 0.1524)
				(type default)
			)
			(layer "B.SilkS")
		)
		(fp_line
			(start 0.7874 0.4064)
			(end 0.7874 -0.4064)
			(stroke
				(width 0.1524)
				(type default)
			)
			(layer "B.SilkS")
		)
		(fp_line
			(start -0.7874 -0.4064)
			(end -0.7874 0.4064)
			(stroke
				(width 0.1524)
				(type default)
			)
			(layer "B.SilkS")
		)
		(fp_line
			(start 0.7874 -0.4064)
			(end -0.7874 -0.4064)
			(stroke
				(width 0.1524)
				(type default)
			)
			(layer "B.SilkS")
		)
		(fp_line
			(start -0.67945 0.3048)
			(end -0.120396 0.3048)
			(stroke
				(width 0.1)
				(type default)
			)
			(layer "B.Fab")
		)
		(fp_line
			(start -0.120396 0.3048)
			(end -0.120396 0.2794)
			(stroke
				(width 0.1)
				(type default)
			)
			(layer "B.Fab")
		)
		(fp_line
			(start 0.12065 0.3048)
			(end 0.67945 0.3048)
			(stroke
				(width 0.1)
				(type default)
			)
			(layer "B.Fab")
		)
		(fp_line
			(start 0.67945 0.3048)
			(end 0.67945 -0.305054)
			(stroke
				(width 0.1)
				(type default)
			)
			(layer "B.Fab")
		)
		(fp_line
			(start -0.120396 0.2794)
			(end 0.12065 0.2794)
			(stroke
				(width 0.1)
				(type default)
			)
			(layer "B.Fab")
		)
		(fp_line
			(start 0.12065 0.2794)
			(end 0.12065 0.3048)
			(stroke
				(width 0.1)
				(type default)
			)
			(layer "B.Fab")
		)
		(fp_line
			(start -0.12065 -0.2794)
			(end -0.12065 -0.3048)
			(stroke
				(width 0.1)
				(type default)
			)
			(layer "B.Fab")
		)
		(fp_line
			(start 0.12065 -0.2794)
			(end -0.12065 -0.2794)
			(stroke
				(width 0.1)
				(type default)
			)
			(layer "B.Fab")
		)
		(fp_line
			(start -0.67945 -0.3048)
			(end -0.67945 0.3048)
			(stroke
				(width 0.1)
				(type default)
			)
			(layer "B.Fab")
		)
		(fp_line
			(start -0.12065 -0.3048)
			(end -0.67945 -0.3048)
			(stroke
				(width 0.1)
				(type default)
			)
			(layer "B.Fab")
		)
		(fp_line
			(start 0.12065 -0.305054)
			(end 0.12065 -0.2794)
			(stroke
				(width 0.1)
				(type default)
			)
			(layer "B.Fab")
		)
		(fp_line
			(start 0.67945 -0.305054)
			(end 0.12065 -0.305054)
			(stroke
				(width 0.1)
				(type default)
			)
			(layer "B.Fab")
		)
		(pad "1" smd circle
			(at 0.40005 0 90)
			(size 0 0)
			(layers "B.Cu" "B.Mask" "B.Paste")
			(net "P3V3_AUX")
		)
		(pad "2" smd circle
			(at -0.40005 0 90)
			(size 0 0)
			(layers "B.Cu" "B.Mask" "B.Paste")
			(net "GND")
		)
	)
	(footprint ""
		(layer "B.Cu")
		(at 184.658 -96.738948)
		(property "Reference" "R245"
			(at 0 0 0)
			(layer "B.SilkS")
			(hide yes)
			(effects
				(font
					(size 1.27 1.27)
				)
				(justify mirror)
			)
		)
		(property "Value" ""
			(at 0 0 0)
			(layer "B.Fab")
			(effects
				(font
					(size 1.27 1.27)
				)
				(justify mirror)
			)
		)
		(duplicate_pad_numbers_are_jumpers no)
		(fp_line
			(start -0.7874 -0.4064)
			(end -0.7874 0.4064)
			(stroke
				(width 0.1524)
				(type default)
			)
			(layer "B.SilkS")
		)
		(fp_line
			(start -0.7874 0.4064)
			(end 0.7874 0.4064)
			(stroke
				(width 0.1524)
				(type default)
			)
			(layer "B.SilkS")
		)
		(fp_line
			(start 0.7874 -0.4064)
			(end -0.7874 -0.4064)
			(stroke
				(width 0.1524)
				(type default)
			)
			(layer "B.SilkS")
		)
		(fp_line
			(start 0.7874 0.4064)
			(end 0.7874 -0.4064)
			(stroke
				(width 0.1524)
				(type default)
			)
			(layer "B.SilkS")
		)
		(fp_line
			(start -0.67945 -0.3048)
			(end -0.67945 0.3048)
			(stroke
				(width 0.1)
				(type default)
			)
			(layer "B.Fab")
		)
		(fp_line
			(start -0.67945 0.3048)
			(end -0.120396 0.3048)
			(stroke
				(width 0.1)
				(type default)
			)
			(layer "B.Fab")
		)
		(fp_line
			(start -0.12065 -0.3048)
			(end -0.67945 -0.3048)
			(stroke
				(width 0.1)
				(type default)
			)
			(layer "B.Fab")
		)
		(fp_line
			(start -0.12065 -0.2794)
			(end -0.12065 -0.3048)
			(stroke
				(width 0.1)
				(type default)
			)
			(layer "B.Fab")
		)
		(fp_line
			(start -0.120396 0.2794)
			(end 0.12065 0.2794)
			(stroke
				(width 0.1)
				(type default)
			)
			(layer "B.Fab")
		)
		(fp_line
			(start -0.120396 0.3048)
			(end -0.120396 0.2794)
			(stroke
				(width 0.1)
				(type default)
			)
			(layer "B.Fab")
		)
		(fp_line
			(start 0.12065 -0.305054)
			(end 0.12065 -0.2794)
			(stroke
				(width 0.1)
				(type default)
			)
			(layer "B.Fab")
		)
		(fp_line
			(start 0.12065 -0.2794)
			(end -0.12065 -0.2794)
			(stroke
				(width 0.1)
				(type default)
			)
			(layer "B.Fab")
		)
		(fp_line
			(start 0.12065 0.2794)
			(end 0.12065 0.3048)
			(stroke
				(width 0.1)
				(type default)
			)
			(layer "B.Fab")
		)
		(fp_line
			(start 0.12065 0.3048)
			(end 0.67945 0.3048)
			(stroke
				(width 0.1)
				(type default)
			)
			(layer "B.Fab")
		)
		(fp_line
			(start 0.67945 -0.305054)
			(end 0.12065 -0.305054)
			(stroke
				(width 0.1)
				(type default)
			)
			(layer "B.Fab")
		)
		(fp_line
			(start 0.67945 0.3048)
			(end 0.67945 -0.305054)
			(stroke
				(width 0.1)
				(type default)
			)
			(layer "B.Fab")
		)
		(pad "1" smd circle
			(at 0.40005 0 180)
			(size 0 0)
			(layers "B.Cu" "B.Mask" "B.Paste")
			(net "IRQ_SMI_ACTIVE_N")
		)
		(pad "2" smd circle
			(at -0.40005 0 180)
			(size 0 0)
			(layers "B.Cu" "B.Mask" "B.Paste")
			(net "IRQ_SMI_ACTIVE_N_R")
		)
	)
	(footprint ""
		(layer "B.Cu")
		(at 287.985454 -190.94831 180)
		(property "Reference" "R293"
			(at 0 0 0)
			(layer "B.SilkS")
			(hide yes)
			(effects
				(font
					(size 1.27 1.27)
				)
				(justify mirror)
			)
		)
		(property "Value" ""
			(at 0 0 0)
			(layer "B.Fab")
			(effects
				(font
					(size 1.27 1.27)
				)
				(justify mirror)
			)
		)
		(duplicate_pad_numbers_are_jumpers no)
		(fp_line
			(start 0.7874 0.4064)
			(end 0.7874 -0.4064)
			(stroke
				(width 0.1524)
				(type default)
			)
			(layer "B.SilkS")
		)
		(fp_line
			(start 0.7874 -0.4064)
			(end -0.7874 -0.4064)
			(stroke
				(width 0.1524)
				(type default)
			)
			(layer "B.SilkS")
		)
		(fp_line
			(start -0.7874 0.4064)
			(end 0.7874 0.4064)
			(stroke
				(width 0.1524)
				(type default)
			)
			(layer "B.SilkS")
		)
		(fp_line
			(start -0.7874 -0.4064)
			(end -0.7874 0.4064)
			(stroke
				(width 0.1524)
				(type default)
			)
			(layer "B.SilkS")
		)
		(fp_line
			(start 0.67945 0.3048)
			(end 0.67945 -0.305054)
			(stroke
				(width 0.1)
				(type default)
			)
			(layer "B.Fab")
		)
		(fp_line
			(start 0.67945 -0.305054)
			(end 0.12065 -0.305054)
			(stroke
				(width 0.1)
				(type default)
			)
			(layer "B.Fab")
		)
		(fp_line
			(start 0.12065 0.3048)
			(end 0.67945 0.3048)
			(stroke
				(width 0.1)
				(type default)
			)
			(layer "B.Fab")
		)
		(fp_line
			(start 0.12065 0.2794)
			(end 0.12065 0.3048)
			(stroke
				(width 0.1)
				(type default)
			)
			(layer "B.Fab")
		)
		(fp_line
			(start 0.12065 -0.2794)
			(end -0.12065 -0.2794)
			(stroke
				(width 0.1)
				(type default)
			)
			(layer "B.Fab")
		)
		(fp_line
			(start 0.12065 -0.305054)
			(end 0.12065 -0.2794)
			(stroke
				(width 0.1)
				(type default)
			)
			(layer "B.Fab")
		)
		(fp_line
			(start -0.120396 0.3048)
			(end -0.120396 0.2794)
			(stroke
				(width 0.1)
				(type default)
			)
			(layer "B.Fab")
		)
		(fp_line
			(start -0.120396 0.2794)
			(end 0.12065 0.2794)
			(stroke
				(width 0.1)
				(type default)
			)
			(layer "B.Fab")
		)
		(fp_line
			(start -0.12065 -0.2794)
			(end -0.12065 -0.3048)
			(stroke
				(width 0.1)
				(type default)
			)
			(layer "B.Fab")
		)
		(fp_line
			(start -0.12065 -0.3048)
			(end -0.67945 -0.3048)
			(stroke
				(width 0.1)
				(type default)
			)
			(layer "B.Fab")
		)
		(fp_line
			(start -0.67945 0.3048)
			(end -0.120396 0.3048)
			(stroke
				(width 0.1)
				(type default)
			)
			(layer "B.Fab")
		)
		(fp_line
			(start -0.67945 -0.3048)
			(end -0.67945 0.3048)
			(stroke
				(width 0.1)
				(type default)
			)
			(layer "B.Fab")
		)
		(pad "1" smd circle
			(at 0.40005 0)
			(size 0 0)
			(layers "B.Cu" "B.Mask" "B.Paste")
			(net "PWRGD_CHC_CPU0_DIMM")
		)
		(pad "2" smd circle
			(at -0.40005 0)
			(size 0 0)
			(layers "B.Cu" "B.Mask" "B.Paste")
			(net "PWRGD_CHAF_CPU0")
		)
	)
	(footprint ""
		(layer "B.Cu")
		(at 346.450158 -248.47931 180)
		(property "Reference" "C275"
			(at 0 0 0)
			(layer "B.SilkS")
			(hide yes)
			(effects
				(font
					(size 1.27 1.27)
				)
				(justify mirror)
			)
		)
		(property "Value" ""
			(at 0 0 0)
			(layer "B.Fab")
			(effects
				(font
					(size 1.27 1.27)
				)
				(justify mirror)
			)
		)
		(duplicate_pad_numbers_are_jumpers no)
		(fp_line
			(start 0.7874 0.4064)
			(end 0.7874 -0.4064)
			(stroke
				(width 0.1524)
				(type default)
			)
			(layer "B.SilkS")
		)
		(fp_line
			(start 0.7874 -0.4064)
			(end -0.7874 -0.4064)
			(stroke
				(width 0.1524)
				(type default)
			)
			(layer "B.SilkS")
		)
		(fp_line
			(start -0.7874 0.4064)
			(end 0.7874 0.4064)
			(stroke
				(width 0.1524)
				(type default)
			)
			(layer "B.SilkS")
		)
		(fp_line
			(start -0.7874 -0.4064)
			(end -0.7874 0.4064)
			(stroke
				(width 0.1524)
				(type default)
			)
			(layer "B.SilkS")
		)
		(fp_line
			(start 0.67945 0.3048)
			(end 0.67945 -0.305054)
			(stroke
				(width 0.1)
				(type default)
			)
			(layer "B.Fab")
		)
		(fp_line
			(start 0.67945 -0.305054)
			(end 0.12065 -0.305054)
			(stroke
				(width 0.1)
				(type default)
			)
			(layer "B.Fab")
		)
		(fp_line
			(start 0.12065 0.3048)
			(end 0.67945 0.3048)
			(stroke
				(width 0.1)
				(type default)
			)
			(layer "B.Fab")
		)
		(fp_line
			(start 0.12065 0.2794)
			(end 0.12065 0.3048)
			(stroke
				(width 0.1)
				(type default)
			)
			(layer "B.Fab")
		)
		(fp_line
			(start 0.12065 -0.2794)
			(end -0.12065 -0.2794)
			(stroke
				(width 0.1)
				(type default)
			)
			(layer "B.Fab")
		)
		(fp_line
			(start 0.12065 -0.305054)
			(end 0.12065 -0.2794)
			(stroke
				(width 0.1)
				(type default)
			)
			(layer "B.Fab")
		)
		(fp_line
			(start -0.120396 0.3048)
			(end -0.120396 0.2794)
			(stroke
				(width 0.1)
				(type default)
			)
			(layer "B.Fab")
		)
		(fp_line
			(start -0.120396 0.2794)
			(end 0.12065 0.2794)
			(stroke
				(width 0.1)
				(type default)
			)
			(layer "B.Fab")
		)
		(fp_line
			(start -0.12065 -0.2794)
			(end -0.12065 -0.3048)
			(stroke
				(width 0.1)
				(type default)
			)
			(layer "B.Fab")
		)
		(fp_line
			(start -0.12065 -0.3048)
			(end -0.67945 -0.3048)
			(stroke
				(width 0.1)
				(type default)
			)
			(layer "B.Fab")
		)
		(fp_line
			(start -0.67945 0.3048)
			(end -0.120396 0.3048)
			(stroke
				(width 0.1)
				(type default)
			)
			(layer "B.Fab")
		)
		(fp_line
			(start -0.67945 -0.3048)
			(end -0.67945 0.3048)
			(stroke
				(width 0.1)
				(type default)
			)
			(layer "B.Fab")
		)
		(pad "1" smd circle
			(at 0.40005 0)
			(size 0 0)
			(layers "B.Cu" "B.Mask" "B.Paste")
			(net "PVDDCR_CPU0_P0")
		)
		(pad "2" smd circle
			(at -0.40005 0)
			(size 0 0)
			(layers "B.Cu" "B.Mask" "B.Paste")
			(net "GND")
		)
	)
	(footprint ""
		(layer "B.Cu")
		(at 217.678 -335.026 180)
		(property "Reference" "R6811"
			(at 0 0 0)
			(layer "B.SilkS")
			(hide yes)
			(effects
				(font
					(size 1.27 1.27)
				)
				(justify mirror)
			)
		)
		(property "Value" ""
			(at 0 0 0)
			(layer "B.Fab")
			(effects
				(font
					(size 1.27 1.27)
				)
				(justify mirror)
			)
		)
		(duplicate_pad_numbers_are_jumpers no)
		(fp_line
			(start 0.32512 0.175006)
			(end 0.32512 -0.175006)
			(stroke
				(width 0.1)
				(type default)
			)
			(layer "B.Fab")
		)
		(fp_line
			(start 0.32512 -0.175006)
			(end -0.32512 -0.175006)
			(stroke
				(width 0.1)
				(type default)
			)
			(layer "B.Fab")
		)
		(fp_line
			(start -0.32512 0.175006)
			(end 0.32512 0.175006)
			(stroke
				(width 0.1)
				(type default)
			)
			(layer "B.Fab")
		)
		(fp_line
			(start -0.32512 -0.175006)
			(end -0.32512 0.175006)
			(stroke
				(width 0.1)
				(type default)
			)
			(layer "B.Fab")
		)
		(pad "1" smd rect
			(at 0.2667 0)
			(size 0.3048 0.381)
			(layers "B.Cu" "B.Mask" "B.Paste")
			(net "SMB_RT_CPU1_P0_R_SCL")
		)
		(pad "2" smd rect
			(at -0.2667 0 180)
			(size 0.3048 0.381)
			(layers "B.Cu" "B.Mask" "B.Paste")
			(net "SMB_RT_CPU1_P0_SCL")
		)
	)
	(footprint ""
		(layer "B.Cu")
		(at 125.389386 -255.845564)
		(property "Reference" "C2447"
			(at 0 0 0)
			(layer "B.SilkS")
			(hide yes)
			(effects
				(font
					(size 1.27 1.27)
				)
				(justify mirror)
			)
		)
		(property "Value" ""
			(at 0 0 0)
			(layer "B.Fab")
			(effects
				(font
					(size 1.27 1.27)
				)
				(justify mirror)
			)
		)
		(duplicate_pad_numbers_are_jumpers no)
		(fp_line
			(start -0.7874 -0.4064)
			(end -0.7874 0.4064)
			(stroke
				(width 0.1524)
				(type default)
			)
			(layer "B.SilkS")
		)
		(fp_line
			(start -0.7874 0.4064)
			(end 0.7874 0.4064)
			(stroke
				(width 0.1524)
				(type default)
			)
			(layer "B.SilkS")
		)
		(fp_line
			(start 0.7874 -0.4064)
			(end -0.7874 -0.4064)
			(stroke
				(width 0.1524)
				(type default)
			)
			(layer "B.SilkS")
		)
		(fp_line
			(start 0.7874 0.4064)
			(end 0.7874 -0.4064)
			(stroke
				(width 0.1524)
				(type default)
			)
			(layer "B.SilkS")
		)
		(fp_line
			(start -0.67945 -0.3048)
			(end -0.67945 0.3048)
			(stroke
				(width 0.1)
				(type default)
			)
			(layer "B.Fab")
		)
		(fp_line
			(start -0.67945 0.3048)
			(end -0.120396 0.3048)
			(stroke
				(width 0.1)
				(type default)
			)
			(layer "B.Fab")
		)
		(fp_line
			(start -0.12065 -0.3048)
			(end -0.67945 -0.3048)
			(stroke
				(width 0.1)
				(type default)
			)
			(layer "B.Fab")
		)
		(fp_line
			(start -0.12065 -0.2794)
			(end -0.12065 -0.3048)
			(stroke
				(width 0.1)
				(type default)
			)
			(layer "B.Fab")
		)
		(fp_line
			(start -0.120396 0.2794)
			(end 0.12065 0.2794)
			(stroke
				(width 0.1)
				(type default)
			)
			(layer "B.Fab")
		)
		(fp_line
			(start -0.120396 0.3048)
			(end -0.120396 0.2794)
			(stroke
				(width 0.1)
				(type default)
			)
			(layer "B.Fab")
		)
		(fp_line
			(start 0.12065 -0.305054)
			(end 0.12065 -0.2794)
			(stroke
				(width 0.1)
				(type default)
			)
			(layer "B.Fab")
		)
		(fp_line
			(start 0.12065 -0.2794)
			(end -0.12065 -0.2794)
			(stroke
				(width 0.1)
				(type default)
			)
			(layer "B.Fab")
		)
		(fp_line
			(start 0.12065 0.2794)
			(end 0.12065 0.3048)
			(stroke
				(width 0.1)
				(type default)
			)
			(layer "B.Fab")
		)
		(fp_line
			(start 0.12065 0.3048)
			(end 0.67945 0.3048)
			(stroke
				(width 0.1)
				(type default)
			)
			(layer "B.Fab")
		)
		(fp_line
			(start 0.67945 -0.305054)
			(end 0.12065 -0.305054)
			(stroke
				(width 0.1)
				(type default)
			)
			(layer "B.Fab")
		)
		(fp_line
			(start 0.67945 0.3048)
			(end 0.67945 -0.305054)
			(stroke
				(width 0.1)
				(type default)
			)
			(layer "B.Fab")
		)
		(pad "1" smd circle
			(at 0.40005 0 180)
			(size 0 0)
			(layers "B.Cu" "B.Mask" "B.Paste")
			(net "PVDDCR_SOC_P1")
		)
		(pad "2" smd circle
			(at -0.40005 0 180)
			(size 0 0)
			(layers "B.Cu" "B.Mask" "B.Paste")
			(net "GND")
		)
	)
)
